# T6G (Grand Teton) — schematic netlist excerpt (pin names and nets, part order shuffled) for the footprints in the layout excerpt that follows; sources: Cadence DE-HDL packaged netlist, KiCad conversion of 04192023_DAF0TMB3IC0_F0TG_MB_C_brd_V02_OCP.brd

PC200  Q_CAP  1UF 16V 10% X6S  pkg C0402  page 207 : A = PVDD11_S3_P0_VCC ; B = GND
R877  Q_RES  0 5% CHIP  pkg 0402LF  page 133 : A = RST_PERST_OCP_SFF_BUF2_N ; B = RST_PERST0_OCP_SFF_N

(kicad_pcb
	(version 20260206)
	(generator "pcbnew")
	(generator_version "10.0")
	(general
		(thickness 1.6)
		(legacy_teardrops no)
	)
	(paper "A4")
	(title_block
		(title "04192023_DAF0TMB3IC0_F0TG_MB_C_brd_V02_OCP.brd")
		(comment 1 "Grand Teton / footprints 2709-2710 of 8354")
	)
	(layers
		(0 "F.Cu" signal "TOP")
		(4 "In1.Cu" signal "GND")
		(6 "In2.Cu" signal "IN1")
		(8 "In3.Cu" signal "GND1")
		(10 "In4.Cu" signal "IN2")
		(12 "In5.Cu" signal "GND2")
		(14 "In6.Cu" signal "IN3")
		(16 "In7.Cu" signal "GND3")
		(18 "In8.Cu" signal "VCC")
		(20 "In9.Cu" signal "VCC1")
		(22 "In10.Cu" signal "GND4")
		(24 "In11.Cu" signal "IN4")
		(26 "In12.Cu" signal "GND5")
		(28 "In13.Cu" signal "IN5")
		(30 "In14.Cu" signal "GND6")
		(32 "In15.Cu" signal "IN6")
		(34 "In16.Cu" signal "GND7")
		(2 "B.Cu" signal "BOTTOM")
		(9 "F.Adhes" user "F.Adhesive")
		(11 "B.Adhes" user "B.Adhesive")
		(13 "F.Paste" user "Package Geometry/Pastemask Top")
		(15 "B.Paste" user "Package Geometry/Pastemask Bottom")
		(5 "F.SilkS" user "Ref Des/Silkscreen Top")
		(7 "B.SilkS" user "Ref Des/Silkscreen Bottom")
		(1 "F.Mask" user "Board Geometry/Soldermask Top")
		(3 "B.Mask" user "Board Geometry/Soldermask Bottom")
		(17 "Dwgs.User" user "User.Drawings")
		(19 "Cmts.User" user "User.Comments")
		(21 "Eco1.User" user "User.Eco1")
		(23 "Eco2.User" user "User.Eco2")
		(25 "Edge.Cuts" user "Board Geometry/Outline")
		(27 "Margin" user)
		(31 "F.CrtYd" user "Package Geometry/Place Bound Top")
		(29 "B.CrtYd" user "Package Geometry/Place Bound Bottom")
		(35 "F.Fab" user "Ref Des/Assembly Top")
		(33 "B.Fab" user "Ref Des/Assembly Bottom")
	)
	(footprint ""
		(layer "F.Cu")
		(at 422.26611 -365.804196 90)
		(property "Reference" "PC200"
			(at 0 0 90)
			(layer "F.SilkS")
			(hide yes)
			(effects
				(font
					(size 1.27 1.27)
				)
			)
		)
		(property "Value" ""
			(at 0 0 90)
			(layer "F.Fab")
			(effects
				(font
					(size 1.27 1.27)
				)
			)
		)
		(duplicate_pad_numbers_are_jumpers no)
		(fp_line
			(start 0.7874 -0.4064)
			(end 0.7874 0.4064)
			(stroke
				(width 0.1524)
				(type default)
			)
			(layer "F.SilkS")
		)
		(fp_line
			(start -0.7874 -0.4064)
			(end 0.7874 -0.4064)
			(stroke
				(width 0.1524)
				(type default)
			)
			(layer "F.SilkS")
		)
		(fp_line
			(start 0.7874 0.4064)
			(end -0.7874 0.4064)
			(stroke
				(width 0.1524)
				(type default)
			)
			(layer "F.SilkS")
		)
		(fp_line
			(start -0.7874 0.4064)
			(end -0.7874 -0.4064)
			(stroke
				(width 0.1524)
				(type default)
			)
			(layer "F.SilkS")
		)
		(fp_line
			(start -0.12065 -0.305054)
			(end -0.12065 -0.2794)
			(stroke
				(width 0.1)
				(type default)
			)
			(layer "F.Fab")
		)
		(fp_line
			(start -0.67945 -0.305054)
			(end -0.12065 -0.305054)
			(stroke
				(width 0.1)
				(type default)
			)
			(layer "F.Fab")
		)
		(fp_line
			(start 0.67945 -0.3048)
			(end 0.67945 0.3048)
			(stroke
				(width 0.1)
				(type default)
			)
			(layer "F.Fab")
		)
		(fp_line
			(start 0.12065 -0.3048)
			(end 0.67945 -0.3048)
			(stroke
				(width 0.1)
				(type default)
			)
			(layer "F.Fab")
		)
		(fp_line
			(start 0.12065 -0.2794)
			(end 0.12065 -0.3048)
			(stroke
				(width 0.1)
				(type default)
			)
			(layer "F.Fab")
		)
		(fp_line
			(start -0.12065 -0.2794)
			(end 0.12065 -0.2794)
			(stroke
				(width 0.1)
				(type default)
			)
			(layer "F.Fab")
		)
		(fp_line
			(start 0.120396 0.2794)
			(end -0.12065 0.2794)
			(stroke
				(width 0.1)
				(type default)
			)
			(layer "F.Fab")
		)
		(fp_line
			(start -0.12065 0.2794)
			(end -0.12065 0.3048)
			(stroke
				(width 0.1)
				(type default)
			)
			(layer "F.Fab")
		)
		(fp_line
			(start 0.67945 0.3048)
			(end 0.120396 0.3048)
			(stroke
				(width 0.1)
				(type default)
			)
			(layer "F.Fab")
		)
		(fp_line
			(start 0.120396 0.3048)
			(end 0.120396 0.2794)
			(stroke
				(width 0.1)
				(type default)
			)
			(layer "F.Fab")
		)
		(fp_line
			(start -0.12065 0.3048)
			(end -0.67945 0.3048)
			(stroke
				(width 0.1)
				(type default)
			)
			(layer "F.Fab")
		)
		(fp_line
			(start -0.67945 0.3048)
			(end -0.67945 -0.305054)
			(stroke
				(width 0.1)
				(type default)
			)
			(layer "F.Fab")
		)
		(pad "1" smd circle
			(at -0.40005 0 90)
			(size 0 0)
			(layers "F.Cu" "F.Mask" "F.Paste")
			(net "PVDD11_S3_P0_VCC")
		)
		(pad "2" smd circle
			(at 0.40005 0 90)
			(size 0 0)
			(layers "F.Cu" "F.Mask" "F.Paste")
			(net "GND")
		)
	)
	(footprint ""
		(layer "F.Cu")
		(at 213.928198 -123.565412)
		(property "Reference" "R877"
			(at 0 0 0)
			(layer "F.SilkS")
			(hide yes)
			(effects
				(font
					(size 1.27 1.27)
				)
			)
		)
		(property "Value" ""
			(at 0 0 0)
			(layer "F.Fab")
			(effects
				(font
					(size 1.27 1.27)
				)
			)
		)
		(duplicate_pad_numbers_are_jumpers no)
		(fp_line
			(start -0.7874 -0.4064)
			(end 0.7874 -0.4064)
			(stroke
				(width 0.1524)
				(type default)
			)
			(layer "F.SilkS")
		)
		(fp_line
			(start -0.7874 0.4064)
			(end -0.7874 -0.4064)
			(stroke
				(width 0.1524)
				(type default)
			)
			(layer "F.SilkS")
		)
		(fp_line
			(start 0.7874 -0.4064)
			(end 0.7874 0.4064)
			(stroke
				(width 0.1524)
				(type default)
			)
			(layer "F.SilkS")
		)
		(fp_line
			(start 0.7874 0.4064)
			(end -0.7874 0.4064)
			(stroke
				(width 0.1524)
				(type default)
			)
			(layer "F.SilkS")
		)
		(fp_line
			(start -0.67945 -0.305054)
			(end -0.12065 -0.305054)
			(stroke
				(width 0.1)
				(type default)
			)
			(layer "F.Fab")
		)
		(fp_line
			(start -0.67945 0.3048)
			(end -0.67945 -0.305054)
			(stroke
				(width 0.1)
				(type default)
			)
			(layer "F.Fab")
		)
		(fp_line
			(start -0.12065 -0.305054)
			(end -0.12065 -0.2794)
			(stroke
				(width 0.1)
				(type default)
			)
			(layer "F.Fab")
		)
		(fp_line
			(start -0.12065 -0.2794)
			(end 0.12065 -0.2794)
			(stroke
				(width 0.1)
				(type default)
			)
			(layer "F.Fab")
		)
		(fp_line
			(start -0.12065 0.2794)
			(end -0.12065 0.3048)
			(stroke
				(width 0.1)
				(type default)
			)
			(layer "F.Fab")
		)
		(fp_line
			(start -0.12065 0.3048)
			(end -0.67945 0.3048)
			(stroke
				(width 0.1)
				(type default)
			)
			(layer "F.Fab")
		)
		(fp_line
			(start 0.120396 0.2794)
			(end -0.12065 0.2794)
			(stroke
				(width 0.1)
				(type default)
			)
			(layer "F.Fab")
		)
		(fp_line
			(start 0.120396 0.3048)
			(end 0.120396 0.2794)
			(stroke
				(width 0.1)
				(type default)
			)
			(layer "F.Fab")
		)
		(fp_line
			(start 0.12065 -0.3048)
			(end 0.67945 -0.3048)
			(stroke
				(width 0.1)
				(type default)
			)
			(layer "F.Fab")
		)
		(fp_line
			(start 0.12065 -0.2794)
			(end 0.12065 -0.3048)
			(stroke
				(width 0.1)
				(type default)
			)
			(layer "F.Fab")
		)
		(fp_line
			(start 0.67945 -0.3048)
			(end 0.67945 0.3048)
			(stroke
				(width 0.1)
				(type default)
			)
			(layer "F.Fab")
		)
		(fp_line
			(start 0.67945 0.3048)
			(end 0.120396 0.3048)
			(stroke
				(width 0.1)
				(type default)
			)
			(layer "F.Fab")
		)
		(pad "1" smd circle
			(at -0.40005 0)
			(size 0 0)
			(layers "F.Cu" "F.Mask" "F.Paste")
			(net "RST_PERST_OCP_SFF_BUF2_N")
		)
		(pad "2" smd circle
			(at 0.40005 0)
			(size 0 0)
			(layers "F.Cu" "F.Mask" "F.Paste")
			(net "RST_PERST0_OCP_SFF_N")
		)
	)
)
